FILE_TYPE = CONNECTIVITY;
{Allegro Design Entry HDL 17.2-2016 S081 (4005846) 1/11/2022}
"PAGE_NUMBER" = 45;
0"NC";
1"P3V3_AUX\g";
2"P3V3_AUX\g";
3"P3V3_AUX\g";
4"GND\g";
5"GND\g";
6"GND\g";
7"GND\g";
8"GND\g";
9"SPI_PCH_IO2_FLASH_R1";
10"SPI_PCH_IO0_FLASH_R1";
11"SPI_PCH_CLK_FLASH_R1";
12"RST_SPI_PCH_FLASH_R1_N";
13"TP_J40_4";
14"TP_J40_13";
15"TP_J40_14";
16"TP_J40_5";
17"TP_J40_6";
18"SPI_PCH_IO1_FLASH_R1";
19"SPI_PCH_CS0_FLASH_R1_N";
20"SPI_PCH_IO3_FLASH_R1";
21"TP_J40_4";
22"TP_J40_12";
23"TP_J40_13";
24"TP_J40_14";
25"TP_J40_12";
26"TP_J40_6";
27"TP_J40_5";
28"SPI_PCH_MUXED_IO2";
29"SPI_PCH_MUXED_CS0_N";
30"SPI_PCH_MUXED_IO3";
31"SPI_PCH_MUXED_IO1";
32"SPI_PCH_MUXED_IO0";
33"SPI_PCH_MUXED_CLK";
34"TP_J40_11";
35"TP_J40_11";
%"Q_RES"
"1","(-1575,1850)","0","pure_quanta","I19";
;
MATERIAL"CHIP"
VALUE"33.2"
TOLERANCE"1%"
PART_NUMBER"CS03322FB03"
PACK_TYPE"0402LF"
WATTAGE"1/16W"
CDS_LIB"pure_quanta"
LOCATION"R486"
$SEC"1"
CDS_SEC"1";
"B"
$PN"2"20;
"A"
$PN"1"30;
%"Q_RES"
"1","(-1575,1900)","0","pure_quanta","I20";
;
VALUE"33.2"
MATERIAL"CHIP"
TOLERANCE"1%"
PART_NUMBER"CS03322FB03"
PACK_TYPE"0402LF"
WATTAGE"1/16W"
CDS_LIB"pure_quanta"
LOCATION"R485"
$SEC"1"
CDS_SEC"1";
"B"
$PN"2"19;
"A"
$PN"1"29;
%"Q_RES"
"1","(-1575,1950)","0","pure_quanta","I21";
;
VALUE"33.2"
MATERIAL"CHIP"
TOLERANCE"1%"
PART_NUMBER"CS03322FB03"
PACK_TYPE"0402LF"
WATTAGE"1/16W"
CDS_LIB"pure_quanta"
LOCATION"R484"
$SEC"1"
CDS_SEC"1";
"B"
$PN"2"18;
"A"
$PN"1"31;
%"Q_RES"
"1","(-1575,2050)","0","pure_quanta","I22";
;
VALUE"33.2"
MATERIAL"CHIP"
TOLERANCE"1%"
PART_NUMBER"CS03322FB03"
PACK_TYPE"0402LF"
WATTAGE"1/16W"
CDS_LIB"pure_quanta"
LOCATION"R482"
$SEC"1"
CDS_SEC"1";
"B"
$PN"2"10;
"A"
$PN"1"32;
%"Q_RES"
"1","(-1575,2000)","0","pure_quanta","I23";
;
MATERIAL"CHIP"
VALUE"33.2"
TOLERANCE"1%"
PART_NUMBER"CS03322FB03"
PACK_TYPE"0402LF"
WATTAGE"1/16W"
CDS_LIB"pure_quanta"
LOCATION"R483"
$SEC"1"
CDS_SEC"1";
"B"
$PN"2"9;
"A"
$PN"1"28;
%"Q_RES"
"1","(-1575,2100)","0","pure_quanta","I24";
;
MATERIAL"CHIP"
VALUE"33.2"
TOLERANCE"1%"
PART_NUMBER"CS03322FB03"
PACK_TYPE"0402LF"
WATTAGE"1/16W"
CDS_LIB"pure_quanta"
LOCATION"R481"
$SEC"1"
CDS_SEC"1";
"B"
$PN"2"11;
"A"
$PN"1"33;
%"Q_RES"
"2","(-1075,2350)","0","pure_quanta","I33";
;
VALUE"4.7K"
MATERIAL"CHIP"
TOLERANCE"1%"
PART_NUMBER"CS24702FB06"
PACK_TYPE"0402LF"
WATTAGE"1/16W"
CDS_LIB"pure_quanta"
LOCATION"R488"
$SEC"1"
CDS_SEC"1";
"A"
$PN"1"2;
"B"
$PN"2"9;
%"Q_RES"
"2","(-850,2350)","0","pure_quanta","I34";
;
MATERIAL"CHIP"
TOLERANCE"1%"
VALUE"4.7K"
PART_NUMBER"CS24702FB06"
PACK_TYPE"0402LF"
WATTAGE"1/16W"
CDS_LIB"pure_quanta"
LOCATION"R490"
$SEC"1"
CDS_SEC"1";
"A"
$PN"1"2;
"B"
$PN"2"19;
%"Q_RES"
"2","(-625,2350)","0","pure_quanta","I35";
;
TOLERANCE"1%"
VALUE"4.7K"
MATERIAL"CHIP"
PART_NUMBER"CS24702FB06"
PACK_TYPE"0402LF"
WATTAGE"1/16W"
CDS_LIB"pure_quanta"
LOCATION"R492"
$SEC"1"
CDS_SEC"1";
"A"
$PN"1"2;
"B"
$PN"2"20;
%"UNIVERSAL_GND"
"1","(1950,1850)","1","logical_power","I40";
;
CDS_LIB"logical_power"
HDL_POWER"GND";
"A"5;
%"Q_CAP"
"1","(-800,3025)","0","pure_quanta","I42";
;
MATERIAL"X6S"
VALUE"1UF"
TOLERANCE"10%"
PACK_TYPE"C0402"
VOLTAGE"25V"
PART_NUMBER"CH5104KEB02"
CDS_LIB"pure_quanta"
LOCATION"C244"
$SEC"1"
CDS_SEC"1";
"B"
$PN"2"6;
"A"
$PN"1"2;
%"UNIVERSAL_GND"
"1","(-800,2825)","0","logical_power","I43";
;
CDS_LIB"logical_power"
HDL_POWER"GND";
"A"6;
%"UNIVERSAL_GND"
"1","(-350,2825)","0","logical_power","I44";
;
CDS_LIB"logical_power"
HDL_POWER"GND";
"A"7;
%"Q_CAP"
"1","(-350,3025)","0","pure_quanta","I45";
;
MATERIAL"X7R"
VALUE"0.01UF"
TOLERANCE"10%"
PACK_TYPE"C0402"
PART_NUMBER"CH31006KB18"
VOLTAGE"50V"
CDS_LIB"pure_quanta"
LOCATION"C246"
$SEC"1"
CDS_SEC"1";
"B"
$PN"2"7;
"A"
$PN"1"2;
%"UNIVERSAL_POWER"
"1","(50,3300)","0","logical_power","I46";
;
HDL_POWER"P3V3_AUX"
CDS_LIB"logical_power";
"A"2;
%"Q_RES"
"2","(3275,2250)","2","pure_quanta","I48";
;
PART_NUMBER"CS24702FB06"
TOLERANCE"1%"
VALUE"4.7K"
MATERIAL"EMPTY"
PACK_TYPE"0402LF"
CDS_LIB"pure_quanta"
WATTAGE"1/16W"
LOCATION"R496"
$SEC"1"
CDS_SEC"1";
"A"
$PN"1"3;
"B"
$PN"2"12;
%"UNIVERSAL_POWER"
"1","(3275,2500)","0","logical_power","I49";
;
HDL_POWER"P3V3_AUX"
CDS_LIB"logical_power";
"A"3;
%"Q_RES"
"2","(-725,1550)","2","pure_quanta","I51";
;
PACK_TYPE"0402LF"
PART_NUMBER"CS24702FB06"
MATERIAL"EMPTY"
TOLERANCE"1%"
VALUE"4.7K"
CDS_LIB"pure_quanta"
WATTAGE"1/16W"
LOCATION"R487"
$SEC"1"
CDS_SEC"1";
"A"
$PN"1"19;
"B"
$PN"2"8;
%"UNIVERSAL_GND"
"1","(-725,1275)","2","logical_power","I52";
;
CDS_LIB"logical_power"
HDL_POWER"GND";
"A"8;
%"SCONN16_ACASPI006P06"
"1","(1375,2050)","0","pure_quanta","I53";
;
PART_TYPE"SMLF"
MATERIAL"IO"
PART_NUMBER"DG016000006"
VALUE"SCONN16_ACA-SPI-006-P06"
CDS_LIB"pure_quanta"
NEEDS_NO_SIZE"TRUE"
CDS_LMAN_SYM_OUTLINE"-350,300,300,-250"
LOCATION"J40"
$SEC"1"
CDS_SEC"1";
"NC8"
$PN"14"24;
"NC7"
$PN"13"23;
"NC6"
$PN"12"25;
"NC4"
$PN"11"35;
"NC3"
$PN"6"26;
"NC2"
$PN"5"27;
"NC1"
$PN"4"21;
"NC0"
$PN"3"12;
"DO"
$PN"8"18;
"GND"
$PN"10"5;
"CLK"
$PN"16"11;
"DI"
$PN"15"10;
"WP_N"
$PN"9"9;
"CS_N"
$PN"7"19;
"HOLD_N"
$PN"1"20;
"VCC"
$PN"2"2;
%"MX25L51245GMI10G"
"1","(1325,750)","0","pure_quanta","I54";
;
PART_TYPE"SMLF"
VALUE"MX25L51245GMI-10G"
PART_NUMBER"AKE3FF00Z00"
MATERIAL"EMPTY"
CDS_LIB"pure_quanta"
NEEDS_NO_SIZE"TRUE"
CDS_LMAN_SYM_OUTLINE"-275,325,275,-325"
$LOCATION"U17"
CDS_LOCATION"U17"
$SEC"1"
CDS_SEC"1";
"SCLK"
$PN"16"11;
"SI_SIO0"
$PN"15"10;
"NC3"
$PN"14"15;
"NC2"
$PN"13"14;
"DNU4"
$PN"12"22;
"DNU3"
$PN"11"34;
"GND"
$PN"10"4;
"WP#_SIO2 \B"
$PN"9"9;
"SO_SIO1"
$PN"8"18;
"CS# \B"
$PN"7"19;
"DNU2"
$PN"6"17;
"DNU1"
$PN"5"16;
"NC1"
$PN"4"13;
"RESET# \B"
$PN"3"12;
"VCC"
$PN"2"1;
"NC_SIO3"
$PN"1"20;
%"UNIVERSAL_POWER"
"1","(875,1200)","0","logical_power","I55";
;
HDL_POWER"P3V3_AUX"
CDS_LIB"logical_power";
"A"1;
%"UNIVERSAL_GND"
"1","(1875,475)","1","logical_power","I56";
;
HDL_POWER"GND"
CDS_LIB"logical_power";
"A"4;
END.
